(kicad_pcb
	(version 20260206)
	(generator "pcbnew")
	(generator_version "10.0")
	(general
		(thickness 1.6)
		(legacy_teardrops no)
	)
	(paper "A4")
	(title_block
		(title "03242023_DA0F0TMBIJ0_F0T_Motherboard_J_brd_V01_OCP.brd")
		(comment 1 "Grand Teton / footprints 4184-4190 of 6105")
	)
	(layers
		(0 "F.Cu" signal "TOP")
		(4 "In1.Cu" signal "GND")
		(6 "In2.Cu" signal "IN1")
		(8 "In3.Cu" signal "GND1")
		(10 "In4.Cu" signal "IN2")
		(12 "In5.Cu" signal "GND2")
		(14 "In6.Cu" signal "IN3")
		(16 "In7.Cu" signal "GND3")
		(18 "In8.Cu" signal "VCC")
		(20 "In9.Cu" signal "VCC1")
		(22 "In10.Cu" signal "GND4")
		(24 "In11.Cu" signal "IN4")
		(26 "In12.Cu" signal "GND5")
		(28 "In13.Cu" signal "IN5")
		(30 "In14.Cu" signal "GND6")
		(32 "In15.Cu" signal "IN6")
		(34 "In16.Cu" signal "GND7")
		(2 "B.Cu" signal "BOTTOM")
		(9 "F.Adhes" user "F.Adhesive")
		(11 "B.Adhes" user "B.Adhesive")
		(13 "F.Paste" user "Package Geometry/Pastemask Top")
		(15 "B.Paste" user "Package Geometry/Pastemask Bottom")
		(5 "F.SilkS" user "Ref Des/Silkscreen Top")
		(7 "B.SilkS" user "Ref Des/Silkscreen Bottom")
		(1 "F.Mask" user "Board Geometry/Soldermask Top")
		(3 "B.Mask" user "Board Geometry/Soldermask Bottom")
		(17 "Dwgs.User" user "User.Drawings")
		(19 "Cmts.User" user "User.Comments")
		(21 "Eco1.User" user "User.Eco1")
		(23 "Eco2.User" user "User.Eco2")
		(25 "Edge.Cuts" user "Board Geometry/Outline")
		(27 "Margin" user)
		(31 "F.CrtYd" user "Package Geometry/Place Bound Top")
		(29 "B.CrtYd" user "Package Geometry/Place Bound Bottom")
		(35 "F.Fab" user "Ref Des/Assembly Top")
		(33 "B.Fab" user "Ref Des/Assembly Bottom")
	)
	(footprint ""
		(layer "B.Cu")
		(at 233.55681 -123.015248 -90)
		(property "Reference" "R572"
			(at 0 0 90)
			(layer "B.SilkS")
			(hide yes)
			(effects
				(font
					(size 1.27 1.27)
				)
				(justify mirror)
			)
		)
		(property "Value" ""
			(at 0 0 90)
			(layer "B.Fab")
			(effects
				(font
					(size 1.27 1.27)
				)
				(justify mirror)
			)
		)
		(duplicate_pad_numbers_are_jumpers no)
		(fp_line
			(start -1.2954 0.5842)
			(end 1.2954 0.5842)
			(stroke
				(width 0.1524)
				(type default)
			)
			(layer "B.SilkS")
		)
		(fp_line
			(start 1.2954 0.5842)
			(end 1.2954 -0.5842)
			(stroke
				(width 0.1524)
				(type default)
			)
			(layer "B.SilkS")
		)
		(fp_line
			(start -1.2954 -0.5842)
			(end -1.2954 0.5842)
			(stroke
				(width 0.1524)
				(type default)
			)
			(layer "B.SilkS")
		)
		(fp_line
			(start 1.2954 -0.5842)
			(end -1.2954 -0.5842)
			(stroke
				(width 0.1524)
				(type default)
			)
			(layer "B.SilkS")
		)
		(fp_line
			(start -0.8636 0.4572)
			(end 0.8636 0.4572)
			(stroke
				(width 0.1)
				(type default)
			)
			(layer "B.Fab")
		)
		(fp_line
			(start 0.8636 0.4572)
			(end 0.8636 0.4318)
			(stroke
				(width 0.1)
				(type default)
			)
			(layer "B.Fab")
		)
		(fp_line
			(start 0.8636 0.4318)
			(end 0.8636 0.4064)
			(stroke
				(width 0.1)
				(type default)
			)
			(layer "B.Fab")
		)
		(fp_line
			(start -1.1938 0.4064)
			(end -0.8636 0.4064)
			(stroke
				(width 0.1)
				(type default)
			)
			(layer "B.Fab")
		)
		(fp_line
			(start -0.8636 0.4064)
			(end -0.8636 0.4572)
			(stroke
				(width 0.1)
				(type default)
			)
			(layer "B.Fab")
		)
		(fp_line
			(start 0.8636 0.4064)
			(end 1.1938 0.4064)
			(stroke
				(width 0.1)
				(type default)
			)
			(layer "B.Fab")
		)
		(fp_line
			(start 1.1938 0.4064)
			(end 1.1938 -0.406654)
			(stroke
				(width 0.1)
				(type default)
			)
			(layer "B.Fab")
		)
		(fp_line
			(start -1.1938 -0.406654)
			(end -1.1938 0.4064)
			(stroke
				(width 0.1)
				(type default)
			)
			(layer "B.Fab")
		)
		(fp_line
			(start -0.8636 -0.406654)
			(end -1.1938 -0.406654)
			(stroke
				(width 0.1)
				(type default)
			)
			(layer "B.Fab")
		)
		(fp_line
			(start 0.8636 -0.406654)
			(end 0.8636 -0.4572)
			(stroke
				(width 0.1)
				(type default)
			)
			(layer "B.Fab")
		)
		(fp_line
			(start 1.1938 -0.406654)
			(end 0.8636 -0.406654)
			(stroke
				(width 0.1)
				(type default)
			)
			(layer "B.Fab")
		)
		(fp_line
			(start -0.8636 -0.4572)
			(end -0.8636 -0.406654)
			(stroke
				(width 0.1)
				(type default)
			)
			(layer "B.Fab")
		)
		(fp_line
			(start 0.8636 -0.4572)
			(end -0.8636 -0.4572)
			(stroke
				(width 0.1)
				(type default)
			)
			(layer "B.Fab")
		)
		(pad "1" smd rect
			(at 0.7366 0 180)
			(size 0.7112 0.8128)
			(layers "B.Cu" "B.Mask" "B.Paste")
			(net "P3V3_DB2000_FB_VDD")
		)
		(pad "2" smd rect
			(at -0.7366 0 180)
			(size 0.7112 0.8128)
			(layers "B.Cu" "B.Mask" "B.Paste")
			(net "P3V3_DB2000_VDDA")
		)
	)
	(footprint ""
		(layer "B.Cu")
		(at 180.155596 -112.175544 180)
		(property "Reference" "C1152"
			(at 0 0 0)
			(layer "B.SilkS")
			(hide yes)
			(effects
				(font
					(size 1.27 1.27)
				)
				(justify mirror)
			)
		)
		(property "Value" ""
			(at 0 0 0)
			(layer "B.Fab")
			(effects
				(font
					(size 1.27 1.27)
				)
				(justify mirror)
			)
		)
		(duplicate_pad_numbers_are_jumpers no)
		(fp_line
			(start 0.69215 0.2921)
			(end 0.69215 -0.2921)
			(stroke
				(width 0.1524)
				(type default)
			)
			(layer "B.SilkS")
		)
		(fp_line
			(start 0.69215 -0.2921)
			(end -0.69215 -0.2921)
			(stroke
				(width 0.1524)
				(type default)
			)
			(layer "B.SilkS")
		)
		(fp_line
			(start -0.69215 0.2921)
			(end 0.69215 0.2921)
			(stroke
				(width 0.1524)
				(type default)
			)
			(layer "B.SilkS")
		)
		(fp_line
			(start -0.69215 -0.2921)
			(end -0.69215 0.2921)
			(stroke
				(width 0.1524)
				(type default)
			)
			(layer "B.SilkS")
		)
		(fp_line
			(start 0.51435 0.2794)
			(end 0.51435 -0.2794)
			(stroke
				(width 0.1)
				(type default)
			)
			(layer "B.Fab")
		)
		(fp_line
			(start 0.51435 -0.2794)
			(end -0.51435 -0.2794)
			(stroke
				(width 0.1)
				(type default)
			)
			(layer "B.Fab")
		)
		(fp_line
			(start -0.51435 0.2794)
			(end 0.51435 0.2794)
			(stroke
				(width 0.1)
				(type default)
			)
			(layer "B.Fab")
		)
		(fp_line
			(start -0.51435 -0.2794)
			(end -0.51435 0.2794)
			(stroke
				(width 0.1)
				(type default)
			)
			(layer "B.Fab")
		)
		(pad "1" smd circle
			(at 0.40005 0)
			(size 0 0)
			(layers "B.Cu" "B.Mask" "B.Paste")
			(net "VCC_PLD_CORE")
		)
		(pad "2" smd circle
			(at -0.40005 0)
			(size 0 0)
			(layers "B.Cu" "B.Mask" "B.Paste")
			(net "GND")
		)
		(zone
			(layer "B.Cu")
			(hatch none 0.5)
			(connect_pads
				(clearance 0)
			)
			(min_thickness 0.25)
			(keepout
				(tracks not_allowed)
				(vias allowed)
				(pads allowed)
				(copperpour not_allowed)
				(footprints allowed)
			)
			(placement
				(enabled no)
				(sheetname "")
			)
			(fill
				(thermal_gap 0.5)
				(thermal_bridge_width 0.5)
				(island_removal_mode 0)
			)
			(polygon
				(pts
					(xy 179.965096 -112.263174) (xy 180.056536 -112.32134) (xy 180.255926 -112.32134) (xy 180.346096 -112.263174)
					(xy 180.346096 -112.087914) (xy 180.255926 -112.029494) (xy 180.056536 -112.029494) (xy 179.965096 -112.08766)
				)
			)
		)
	)
	(footprint ""
		(layer "B.Cu")
		(at 251.144786 -86.816946)
		(property "Reference" "R1502"
			(at 0 0 0)
			(layer "B.SilkS")
			(hide yes)
			(effects
				(font
					(size 1.27 1.27)
				)
				(justify mirror)
			)
		)
		(property "Value" ""
			(at 0 0 0)
			(layer "B.Fab")
			(effects
				(font
					(size 1.27 1.27)
				)
				(justify mirror)
			)
		)
		(duplicate_pad_numbers_are_jumpers no)
		(fp_line
			(start -0.7874 -0.4064)
			(end -0.7874 0.4064)
			(stroke
				(width 0.1524)
				(type default)
			)
			(layer "B.SilkS")
		)
		(fp_line
			(start -0.7874 0.4064)
			(end 0.7874 0.4064)
			(stroke
				(width 0.1524)
				(type default)
			)
			(layer "B.SilkS")
		)
		(fp_line
			(start 0.7874 -0.4064)
			(end -0.7874 -0.4064)
			(stroke
				(width 0.1524)
				(type default)
			)
			(layer "B.SilkS")
		)
		(fp_line
			(start 0.7874 0.4064)
			(end 0.7874 -0.4064)
			(stroke
				(width 0.1524)
				(type default)
			)
			(layer "B.SilkS")
		)
		(fp_line
			(start -0.67945 -0.3048)
			(end -0.67945 0.3048)
			(stroke
				(width 0.1)
				(type default)
			)
			(layer "B.Fab")
		)
		(fp_line
			(start -0.67945 0.3048)
			(end -0.120396 0.3048)
			(stroke
				(width 0.1)
				(type default)
			)
			(layer "B.Fab")
		)
		(fp_line
			(start -0.12065 -0.3048)
			(end -0.67945 -0.3048)
			(stroke
				(width 0.1)
				(type default)
			)
			(layer "B.Fab")
		)
		(fp_line
			(start -0.12065 -0.2794)
			(end -0.12065 -0.3048)
			(stroke
				(width 0.1)
				(type default)
			)
			(layer "B.Fab")
		)
		(fp_line
			(start -0.120396 0.2794)
			(end 0.12065 0.2794)
			(stroke
				(width 0.1)
				(type default)
			)
			(layer "B.Fab")
		)
		(fp_line
			(start -0.120396 0.3048)
			(end -0.120396 0.2794)
			(stroke
				(width 0.1)
				(type default)
			)
			(layer "B.Fab")
		)
		(fp_line
			(start 0.12065 -0.305054)
			(end 0.12065 -0.2794)
			(stroke
				(width 0.1)
				(type default)
			)
			(layer "B.Fab")
		)
		(fp_line
			(start 0.12065 -0.2794)
			(end -0.12065 -0.2794)
			(stroke
				(width 0.1)
				(type default)
			)
			(layer "B.Fab")
		)
		(fp_line
			(start 0.12065 0.2794)
			(end 0.12065 0.3048)
			(stroke
				(width 0.1)
				(type default)
			)
			(layer "B.Fab")
		)
		(fp_line
			(start 0.12065 0.3048)
			(end 0.67945 0.3048)
			(stroke
				(width 0.1)
				(type default)
			)
			(layer "B.Fab")
		)
		(fp_line
			(start 0.67945 -0.305054)
			(end 0.12065 -0.305054)
			(stroke
				(width 0.1)
				(type default)
			)
			(layer "B.Fab")
		)
		(fp_line
			(start 0.67945 0.3048)
			(end 0.67945 -0.305054)
			(stroke
				(width 0.1)
				(type default)
			)
			(layer "B.Fab")
		)
		(pad "1" smd circle
			(at 0.40005 0 180)
			(size 0 0)
			(layers "B.Cu" "B.Mask" "B.Paste")
			(net "FM_CLK_CK440_SS_EN")
		)
		(pad "2" smd circle
			(at -0.40005 0 180)
			(size 0 0)
			(layers "B.Cu" "B.Mask" "B.Paste")
			(net "GND")
		)
	)
	(footprint ""
		(layer "B.Cu")
		(at 450.732398 -76.719176 90)
		(property "Reference" "R3118"
			(at 0 0 90)
			(layer "B.SilkS")
			(hide yes)
			(effects
				(font
					(size 1.27 1.27)
				)
				(justify mirror)
			)
		)
		(property "Value" ""
			(at 0 0 90)
			(layer "B.Fab")
			(effects
				(font
					(size 1.27 1.27)
				)
				(justify mirror)
			)
		)
		(duplicate_pad_numbers_are_jumpers no)
		(fp_line
			(start 0.7874 -0.4064)
			(end -0.7874 -0.4064)
			(stroke
				(width 0.1524)
				(type default)
			)
			(layer "B.SilkS")
		)
		(fp_line
			(start -0.7874 -0.4064)
			(end -0.7874 0.4064)
			(stroke
				(width 0.1524)
				(type default)
			)
			(layer "B.SilkS")
		)
		(fp_line
			(start 0.7874 0.4064)
			(end 0.7874 -0.4064)
			(stroke
				(width 0.1524)
				(type default)
			)
			(layer "B.SilkS")
		)
		(fp_line
			(start -0.7874 0.4064)
			(end 0.7874 0.4064)
			(stroke
				(width 0.1524)
				(type default)
			)
			(layer "B.SilkS")
		)
		(fp_line
			(start 0.67945 -0.305054)
			(end 0.12065 -0.305054)
			(stroke
				(width 0.1)
				(type default)
			)
			(layer "B.Fab")
		)
		(fp_line
			(start 0.12065 -0.305054)
			(end 0.12065 -0.2794)
			(stroke
				(width 0.1)
				(type default)
			)
			(layer "B.Fab")
		)
		(fp_line
			(start -0.12065 -0.3048)
			(end -0.67945 -0.3048)
			(stroke
				(width 0.1)
				(type default)
			)
			(layer "B.Fab")
		)
		(fp_line
			(start -0.67945 -0.3048)
			(end -0.67945 0.3048)
			(stroke
				(width 0.1)
				(type default)
			)
			(layer "B.Fab")
		)
		(fp_line
			(start 0.12065 -0.2794)
			(end -0.12065 -0.2794)
			(stroke
				(width 0.1)
				(type default)
			)
			(layer "B.Fab")
		)
		(fp_line
			(start -0.12065 -0.2794)
			(end -0.12065 -0.3048)
			(stroke
				(width 0.1)
				(type default)
			)
			(layer "B.Fab")
		)
		(fp_line
			(start 0.12065 0.2794)
			(end 0.12065 0.3048)
			(stroke
				(width 0.1)
				(type default)
			)
			(layer "B.Fab")
		)
		(fp_line
			(start -0.120396 0.2794)
			(end 0.12065 0.2794)
			(stroke
				(width 0.1)
				(type default)
			)
			(layer "B.Fab")
		)
		(fp_line
			(start 0.67945 0.3048)
			(end 0.67945 -0.305054)
			(stroke
				(width 0.1)
				(type default)
			)
			(layer "B.Fab")
		)
		(fp_line
			(start 0.12065 0.3048)
			(end 0.67945 0.3048)
			(stroke
				(width 0.1)
				(type default)
			)
			(layer "B.Fab")
		)
		(fp_line
			(start -0.120396 0.3048)
			(end -0.120396 0.2794)
			(stroke
				(width 0.1)
				(type default)
			)
			(layer "B.Fab")
		)
		(fp_line
			(start -0.67945 0.3048)
			(end -0.120396 0.3048)
			(stroke
				(width 0.1)
				(type default)
			)
			(layer "B.Fab")
		)
		(pad "1" smd circle
			(at 0.40005 0 270)
			(size 0 0)
			(layers "B.Cu" "B.Mask" "B.Paste")
			(net "P3V3_AUX_EN")
		)
		(pad "2" smd circle
			(at -0.40005 0 270)
			(size 0 0)
			(layers "B.Cu" "B.Mask" "B.Paste")
			(net "GND")
		)
	)
	(footprint ""
		(layer "B.Cu")
		(at 354.219764 -333.639922 90)
		(property "Reference" "PC306_P0_2"
			(at 0 0 90)
			(layer "B.SilkS")
			(hide yes)
			(effects
				(font
					(size 1.27 1.27)
				)
				(justify mirror)
			)
		)
		(property "Value" ""
			(at 0 0 90)
			(layer "B.Fab")
			(effects
				(font
					(size 1.27 1.27)
				)
				(justify mirror)
			)
		)
		(duplicate_pad_numbers_are_jumpers no)
		(fp_line
			(start 1.524 -0.762)
			(end -1.524 -0.762)
			(stroke
				(width 0.1524)
				(type default)
			)
			(layer "B.SilkS")
		)
		(fp_line
			(start -1.524 -0.762)
			(end -1.524 0.762)
			(stroke
				(width 0.1524)
				(type default)
			)
			(layer "B.SilkS")
		)
		(fp_line
			(start 1.524 0.762)
			(end 1.524 -0.762)
			(stroke
				(width 0.1524)
				(type default)
			)
			(layer "B.SilkS")
		)
		(fp_line
			(start -1.524 0.762)
			(end 1.524 0.762)
			(stroke
				(width 0.1524)
				(type default)
			)
			(layer "B.SilkS")
		)
		(fp_line
			(start 1.1049 -0.724916)
			(end 1.1049 0.724916)
			(stroke
				(width 0.1)
				(type default)
			)
			(layer "B.Fab")
		)
		(fp_line
			(start -1.1049 -0.724916)
			(end 1.1049 -0.724916)
			(stroke
				(width 0.1)
				(type default)
			)
			(layer "B.Fab")
		)
		(fp_line
			(start 1.1049 0.724916)
			(end -1.1049 0.724916)
			(stroke
				(width 0.1)
				(type default)
			)
			(layer "B.Fab")
		)
		(fp_line
			(start -1.1049 0.724916)
			(end -1.1049 -0.724916)
			(stroke
				(width 0.1)
				(type default)
			)
			(layer "B.Fab")
		)
		(pad "1" smd rect
			(at 0.889 0 90)
			(size 1.016 1.27)
			(layers "B.Cu" "B.Mask" "B.Paste")
			(net "SW_P12V_PVCCIN_CPU0_FLT")
		)
		(pad "2" smd rect
			(at -0.889 0 90)
			(size 1.016 1.27)
			(layers "B.Cu" "B.Mask" "B.Paste")
			(net "GND")
		)
	)
	(footprint ""
		(layer "B.Cu")
		(at 131.93522 -24.100028 180)
		(property "Reference" "C2289"
			(at 0 0 0)
			(layer "B.SilkS")
			(hide yes)
			(effects
				(font
					(size 1.27 1.27)
				)
				(justify mirror)
			)
		)
		(property "Value" ""
			(at 0 0 0)
			(layer "B.Fab")
			(effects
				(font
					(size 1.27 1.27)
				)
				(justify mirror)
			)
		)
		(duplicate_pad_numbers_are_jumpers no)
		(fp_line
			(start 0.299974 0.150114)
			(end 0.299974 -0.150114)
			(stroke
				(width 0.1)
				(type default)
			)
			(layer "B.Fab")
		)
		(fp_line
			(start 0.299974 -0.150114)
			(end -0.299974 -0.150114)
			(stroke
				(width 0.1)
				(type default)
			)
			(layer "B.Fab")
		)
		(fp_line
			(start -0.299974 0.150114)
			(end 0.299974 0.150114)
			(stroke
				(width 0.1)
				(type default)
			)
			(layer "B.Fab")
		)
		(fp_line
			(start -0.299974 -0.150114)
			(end -0.299974 0.150114)
			(stroke
				(width 0.1)
				(type default)
			)
			(layer "B.Fab")
		)
		(pad "1" smd rect
			(at 0.2667 0)
			(size 0.3048 0.381)
			(layers "B.Cu" "B.Mask" "B.Paste")
			(net "USB3_PCH_TX_BUF_DP<4>")
		)
		(pad "2" smd rect
			(at -0.2667 0)
			(size 0.3048 0.381)
			(layers "B.Cu" "B.Mask" "B.Paste")
			(net "USB3_PCH_TX_BUF_C_DP<4>")
		)
	)
	(footprint ""
		(layer "B.Cu")
		(at 320.178176 -58.298588 -90)
		(property "Reference" "R3042"
			(at 0 0 90)
			(layer "B.SilkS")
			(hide yes)
			(effects
				(font
					(size 1.27 1.27)
				)
				(justify mirror)
			)
		)
		(property "Value" ""
			(at 0 0 90)
			(layer "B.Fab")
			(effects
				(font
					(size 1.27 1.27)
				)
				(justify mirror)
			)
		)
		(duplicate_pad_numbers_are_jumpers no)
		(fp_line
			(start -0.7874 0.4064)
			(end 0.7874 0.4064)
			(stroke
				(width 0.1524)
				(type default)
			)
			(layer "B.SilkS")
		)
		(fp_line
			(start 0.7874 0.4064)
			(end 0.7874 -0.4064)
			(stroke
				(width 0.1524)
				(type default)
			)
			(layer "B.SilkS")
		)
		(fp_line
			(start -0.7874 -0.4064)
			(end -0.7874 0.4064)
			(stroke
				(width 0.1524)
				(type default)
			)
			(layer "B.SilkS")
		)
		(fp_line
			(start 0.7874 -0.4064)
			(end -0.7874 -0.4064)
			(stroke
				(width 0.1524)
				(type default)
			)
			(layer "B.SilkS")
		)
		(fp_line
			(start -0.67945 0.3048)
			(end -0.120396 0.3048)
			(stroke
				(width 0.1)
				(type default)
			)
			(layer "B.Fab")
		)
		(fp_line
			(start -0.120396 0.3048)
			(end -0.120396 0.2794)
			(stroke
				(width 0.1)
				(type default)
			)
			(layer "B.Fab")
		)
		(fp_line
			(start 0.12065 0.3048)
			(end 0.67945 0.3048)
			(stroke
				(width 0.1)
				(type default)
			)
			(layer "B.Fab")
		)
		(fp_line
			(start 0.67945 0.3048)
			(end 0.67945 -0.305054)
			(stroke
				(width 0.1)
				(type default)
			)
			(layer "B.Fab")
		)
		(fp_line
			(start -0.120396 0.2794)
			(end 0.12065 0.2794)
			(stroke
				(width 0.1)
				(type default)
			)
			(layer "B.Fab")
		)
		(fp_line
			(start 0.12065 0.2794)
			(end 0.12065 0.3048)
			(stroke
				(width 0.1)
				(type default)
			)
			(layer "B.Fab")
		)
		(fp_line
			(start -0.12065 -0.2794)
			(end -0.12065 -0.3048)
			(stroke
				(width 0.1)
				(type default)
			)
			(layer "B.Fab")
		)
		(fp_line
			(start 0.12065 -0.2794)
			(end -0.12065 -0.2794)
			(stroke
				(width 0.1)
				(type default)
			)
			(layer "B.Fab")
		)
		(fp_line
			(start -0.67945 -0.3048)
			(end -0.67945 0.3048)
			(stroke
				(width 0.1)
				(type default)
			)
			(layer "B.Fab")
		)
		(fp_line
			(start -0.12065 -0.3048)
			(end -0.67945 -0.3048)
			(stroke
				(width 0.1)
				(type default)
			)
			(layer "B.Fab")
		)
		(fp_line
			(start 0.12065 -0.305054)
			(end 0.12065 -0.2794)
			(stroke
				(width 0.1)
				(type default)
			)
			(layer "B.Fab")
		)
		(fp_line
			(start 0.67945 -0.305054)
			(end 0.12065 -0.305054)
			(stroke
				(width 0.1)
				(type default)
			)
			(layer "B.Fab")
		)
		(pad "1" smd circle
			(at 0.40005 0 90)
			(size 0 0)
			(layers "B.Cu" "B.Mask" "B.Paste")
			(net "P1V05_PCH_AUX")
		)
		(pad "2" smd circle
			(at -0.40005 0 90)
			(size 0 0)
			(layers "B.Cu" "B.Mask" "B.Paste")
			(net "H_CPU_ERR1_PCH_R_N")
		)
	)
)
